# S9S_MB_2U (Grand Teton) — schematic netlist excerpt (pin names and nets, part order shuffled) for the footprints in the layout excerpt that follows; sources: Cadence DE-HDL packaged netlist, KiCad conversion of 03242023_DA0F0TMBIJ0_F0T_Motherboard_J_brd_V01_OCP.brd

R4045  Q_RES  33.2 1% CHIP  pkg 0402LF  page 225 : A = RST_CPU0_DRAM_GH_PLD_LVT3_R_N ; B = RST_CPU0_DRAM_GH_PLD_LVT3_N
R2832  Q_RES  100K 1% CHIP  pkg 0402LF  page 148 : A = P3V3_AUX ; B = FM_SWB_BIC_READY_N

(kicad_pcb
	(version 20260206)
	(generator "pcbnew")
	(generator_version "10.0")
	(general
		(thickness 1.6)
		(legacy_teardrops no)
	)
	(paper "A4")
	(title_block
		(title "03242023_DA0F0TMBIJ0_F0T_Motherboard_J_brd_V01_OCP.brd")
		(comment 1 "Grand Teton / footprints 2755-2756 of 6105")
	)
	(layers
		(0 "F.Cu" signal "TOP")
		(4 "In1.Cu" signal "GND")
		(6 "In2.Cu" signal "IN1")
		(8 "In3.Cu" signal "GND1")
		(10 "In4.Cu" signal "IN2")
		(12 "In5.Cu" signal "GND2")
		(14 "In6.Cu" signal "IN3")
		(16 "In7.Cu" signal "GND3")
		(18 "In8.Cu" signal "VCC")
		(20 "In9.Cu" signal "VCC1")
		(22 "In10.Cu" signal "GND4")
		(24 "In11.Cu" signal "IN4")
		(26 "In12.Cu" signal "GND5")
		(28 "In13.Cu" signal "IN5")
		(30 "In14.Cu" signal "GND6")
		(32 "In15.Cu" signal "IN6")
		(34 "In16.Cu" signal "GND7")
		(2 "B.Cu" signal "BOTTOM")
		(9 "F.Adhes" user "F.Adhesive")
		(11 "B.Adhes" user "B.Adhesive")
		(13 "F.Paste" user "Package Geometry/Pastemask Top")
		(15 "B.Paste" user "Package Geometry/Pastemask Bottom")
		(5 "F.SilkS" user "Ref Des/Silkscreen Top")
		(7 "B.SilkS" user "Ref Des/Silkscreen Bottom")
		(1 "F.Mask" user "Board Geometry/Soldermask Top")
		(3 "B.Mask" user "Board Geometry/Soldermask Bottom")
		(17 "Dwgs.User" user "User.Drawings")
		(19 "Cmts.User" user "User.Comments")
		(21 "Eco1.User" user "User.Eco1")
		(23 "Eco2.User" user "User.Eco2")
		(25 "Edge.Cuts" user "Board Geometry/Outline")
		(27 "Margin" user)
		(31 "F.CrtYd" user "Package Geometry/Place Bound Top")
		(29 "B.CrtYd" user "Package Geometry/Place Bound Bottom")
		(35 "F.Fab" user "Ref Des/Assembly Top")
		(33 "B.Fab" user "Ref Des/Assembly Bottom")
	)
	(footprint ""
		(layer "F.Cu")
		(at 424.204892 -392.648948)
		(property "Reference" "R2832"
			(at 0 0 0)
			(layer "F.SilkS")
			(hide yes)
			(effects
				(font
					(size 1.27 1.27)
				)
			)
		)
		(property "Value" ""
			(at 0 0 0)
			(layer "F.Fab")
			(effects
				(font
					(size 1.27 1.27)
				)
			)
		)
		(duplicate_pad_numbers_are_jumpers no)
		(fp_line
			(start -0.7874 -0.4064)
			(end 0.7874 -0.4064)
			(stroke
				(width 0.1524)
				(type default)
			)
			(layer "F.SilkS")
		)
		(fp_line
			(start -0.7874 0.4064)
			(end -0.7874 -0.4064)
			(stroke
				(width 0.1524)
				(type default)
			)
			(layer "F.SilkS")
		)
		(fp_line
			(start 0.7874 -0.4064)
			(end 0.7874 0.4064)
			(stroke
				(width 0.1524)
				(type default)
			)
			(layer "F.SilkS")
		)
		(fp_line
			(start 0.7874 0.4064)
			(end -0.7874 0.4064)
			(stroke
				(width 0.1524)
				(type default)
			)
			(layer "F.SilkS")
		)
		(fp_line
			(start -0.67945 -0.305054)
			(end -0.12065 -0.305054)
			(stroke
				(width 0.1)
				(type default)
			)
			(layer "F.Fab")
		)
		(fp_line
			(start -0.67945 0.3048)
			(end -0.67945 -0.305054)
			(stroke
				(width 0.1)
				(type default)
			)
			(layer "F.Fab")
		)
		(fp_line
			(start -0.12065 -0.305054)
			(end -0.12065 -0.2794)
			(stroke
				(width 0.1)
				(type default)
			)
			(layer "F.Fab")
		)
		(fp_line
			(start -0.12065 -0.2794)
			(end 0.12065 -0.2794)
			(stroke
				(width 0.1)
				(type default)
			)
			(layer "F.Fab")
		)
		(fp_line
			(start -0.12065 0.2794)
			(end -0.12065 0.3048)
			(stroke
				(width 0.1)
				(type default)
			)
			(layer "F.Fab")
		)
		(fp_line
			(start -0.12065 0.3048)
			(end -0.67945 0.3048)
			(stroke
				(width 0.1)
				(type default)
			)
			(layer "F.Fab")
		)
		(fp_line
			(start 0.120396 0.2794)
			(end -0.12065 0.2794)
			(stroke
				(width 0.1)
				(type default)
			)
			(layer "F.Fab")
		)
		(fp_line
			(start 0.120396 0.3048)
			(end 0.120396 0.2794)
			(stroke
				(width 0.1)
				(type default)
			)
			(layer "F.Fab")
		)
		(fp_line
			(start 0.12065 -0.3048)
			(end 0.67945 -0.3048)
			(stroke
				(width 0.1)
				(type default)
			)
			(layer "F.Fab")
		)
		(fp_line
			(start 0.12065 -0.2794)
			(end 0.12065 -0.3048)
			(stroke
				(width 0.1)
				(type default)
			)
			(layer "F.Fab")
		)
		(fp_line
			(start 0.67945 -0.3048)
			(end 0.67945 0.3048)
			(stroke
				(width 0.1)
				(type default)
			)
			(layer "F.Fab")
		)
		(fp_line
			(start 0.67945 0.3048)
			(end 0.120396 0.3048)
			(stroke
				(width 0.1)
				(type default)
			)
			(layer "F.Fab")
		)
		(pad "1" smd circle
			(at -0.40005 0)
			(size 0 0)
			(layers "F.Cu" "F.Mask" "F.Paste")
			(net "P3V3_AUX")
		)
		(pad "2" smd circle
			(at 0.40005 0)
			(size 0 0)
			(layers "F.Cu" "F.Mask" "F.Paste")
			(net "FM_SWB_BIC_READY_N")
		)
	)
	(footprint ""
		(layer "F.Cu")
		(at 116.21008 -106.238548 -90)
		(property "Reference" "R4045"
			(at 0 0 270)
			(layer "F.SilkS")
			(hide yes)
			(effects
				(font
					(size 1.27 1.27)
				)
			)
		)
		(property "Value" ""
			(at 0 0 270)
			(layer "F.Fab")
			(effects
				(font
					(size 1.27 1.27)
				)
			)
		)
		(duplicate_pad_numbers_are_jumpers no)
		(fp_line
			(start -0.7874 0.4064)
			(end -0.7874 -0.4064)
			(stroke
				(width 0.1524)
				(type default)
			)
			(layer "F.SilkS")
		)
		(fp_line
			(start 0.7874 0.4064)
			(end -0.7874 0.4064)
			(stroke
				(width 0.1524)
				(type default)
			)
			(layer "F.SilkS")
		)
		(fp_line
			(start -0.7874 -0.4064)
			(end 0.7874 -0.4064)
			(stroke
				(width 0.1524)
				(type default)
			)
			(layer "F.SilkS")
		)
		(fp_line
			(start 0.7874 -0.4064)
			(end 0.7874 0.4064)
			(stroke
				(width 0.1524)
				(type default)
			)
			(layer "F.SilkS")
		)
		(fp_line
			(start -0.67945 0.3048)
			(end -0.67945 -0.305054)
			(stroke
				(width 0.1)
				(type default)
			)
			(layer "F.Fab")
		)
		(fp_line
			(start -0.12065 0.3048)
			(end -0.67945 0.3048)
			(stroke
				(width 0.1)
				(type default)
			)
			(layer "F.Fab")
		)
		(fp_line
			(start 0.120396 0.3048)
			(end 0.120396 0.2794)
			(stroke
				(width 0.1)
				(type default)
			)
			(layer "F.Fab")
		)
		(fp_line
			(start 0.67945 0.3048)
			(end 0.120396 0.3048)
			(stroke
				(width 0.1)
				(type default)
			)
			(layer "F.Fab")
		)
		(fp_line
			(start -0.12065 0.2794)
			(end -0.12065 0.3048)
			(stroke
				(width 0.1)
				(type default)
			)
			(layer "F.Fab")
		)
		(fp_line
			(start 0.120396 0.2794)
			(end -0.12065 0.2794)
			(stroke
				(width 0.1)
				(type default)
			)
			(layer "F.Fab")
		)
		(fp_line
			(start -0.12065 -0.2794)
			(end 0.12065 -0.2794)
			(stroke
				(width 0.1)
				(type default)
			)
			(layer "F.Fab")
		)
		(fp_line
			(start 0.12065 -0.2794)
			(end 0.12065 -0.3048)
			(stroke
				(width 0.1)
				(type default)
			)
			(layer "F.Fab")
		)
		(fp_line
			(start 0.12065 -0.3048)
			(end 0.67945 -0.3048)
			(stroke
				(width 0.1)
				(type default)
			)
			(layer "F.Fab")
		)
		(fp_line
			(start 0.67945 -0.3048)
			(end 0.67945 0.3048)
			(stroke
				(width 0.1)
				(type default)
			)
			(layer "F.Fab")
		)
		(fp_line
			(start -0.67945 -0.305054)
			(end -0.12065 -0.305054)
			(stroke
				(width 0.1)
				(type default)
			)
			(layer "F.Fab")
		)
		(fp_line
			(start -0.12065 -0.305054)
			(end -0.12065 -0.2794)
			(stroke
				(width 0.1)
				(type default)
			)
			(layer "F.Fab")
		)
		(pad "1" smd circle
			(at -0.40005 0 270)
			(size 0 0)
			(layers "F.Cu" "F.Mask" "F.Paste")
			(net "RST_CPU0_DRAM_GH_PLD_LVT3_R_N")
		)
		(pad "2" smd circle
			(at 0.40005 0 270)
			(size 0 0)
			(layers "F.Cu" "F.Mask" "F.Paste")
			(net "RST_CPU0_DRAM_GH_PLD_LVT3_N")
		)
	)
)
